(kicad_pcb
	(version 20211014)
	(generator pcbnew)
	(general
    (thickness 1.6)
  )
	(paper "A4")
	(title_block
    (title "SA800U (Snapdragon 845) Baseboard")
    (date "2023-10-19")
    (rev "1.0.3")
    (company "Antmicro Ltd.")
    (comment 1 "www.antmicro.com")
		(comment 9 "footprints 101-104 of 589")
	)
	(layers
    (0 "F.Cu" signal)
    (1 "In1.Cu" power)
    (2 "In2.Cu" signal)
    (3 "In3.Cu" signal)
    (4 "In4.Cu" power)
    (31 "B.Cu" signal)
    (32 "B.Adhes" user "B.Adhesive")
    (33 "F.Adhes" user "F.Adhesive")
    (34 "B.Paste" user)
    (35 "F.Paste" user)
    (36 "B.SilkS" user "B.Silkscreen")
    (37 "F.SilkS" user "F.Silkscreen")
    (38 "B.Mask" user)
    (39 "F.Mask" user)
    (40 "Dwgs.User" user "User.Drawings")
    (41 "Cmts.User" user "User.Comments")
    (42 "Eco1.User" user "User.Eco1")
    (43 "Eco2.User" user "User.Eco2")
    (44 "Edge.Cuts" user)
    (45 "Margin" user)
    (46 "B.CrtYd" user "B.Courtyard")
    (47 "F.CrtYd" user "F.Courtyard")
    (48 "B.Fab" user)
    (49 "F.Fab" user)
  )
	(footprint "sa800u-baseboard-hw-footprints:C_0402_1005Metric" (layer "F.Cu")
    (tedit 616D63CF)
    (at 132.9 137.3)
    (descr "Capacitor SMD 0402")
    (tags "capacitor SMD 0402")
    (property "Author" "Antmicro")
    (property "Dielectric" "X5R")
    (property "License" "Apache-2.0")
    (property "MPN" "GRM155R61H104KE14D")
    (property "Manufacturer" "Murata")
    (property "Sheetfile" "usb-c-interface.kicad_sch")
    (property "Sheetname" "USB-C Interface ")
    (property "Val" "100n")
    (property "Voltage" "50V")
    (attr smd)
    (fp_text reference "C69" (at -1.11 -0.62) (layer "F.SilkS")
      (effects (font (size 0.7 0.7) (thickness 0.15)) (justify left bottom))
    )
    (fp_text value "C_100n_0402" (at 0 1.4) (layer "F.Fab")
      (effects (font (size 0.7 0.7) (thickness 0.15)) (justify left bottom))
    )
    (fp_text user "${REFERENCE}" (at -0.932 3.168) (layer "F.Fab") hide
      (effects (font (size 0.7 0.7) (thickness 0.15)) (justify left bottom))
    )
    (fp_text user "License: Apache-2.0" (at -0.932 5.17) (layer "F.Fab") hide
      (effects (font (size 0.7 0.7) (thickness 0.15)) (justify left bottom))
    )
    (fp_text user "Author: Antmicro" (at -0.932 4.17) (layer "F.Fab") hide
      (effects (font (size 0.7 0.7) (thickness 0.15)) (justify left bottom))
    )
    (fp_rect (start -0.94 -0.47) (end 0.94 0.47) (layer "F.CrtYd") (width 0.05) (fill none))
    (fp_rect (start -0.499 -0.249) (end 0.499 0.249) (layer "F.Fab") (width 0.15) (fill none))
    (pad "1" smd roundrect (at -0.484 0) (size 0.59 0.64) (layers "F.Cu" "F.Paste" "F.Mask") (roundrect_rratio 0.25)
      (net 228 "/USB-C Interface /5V0_DBG") (pintype "passive"))
    (pad "2" smd roundrect (at 0.484 0) (size 0.59 0.64) (layers "F.Cu" "F.Paste" "F.Mask") (roundrect_rratio 0.25)
      (net 1 "GND") (pintype "passive"))
  )
	(footprint "sa800u-baseboard-hw-footprints:D_SOD-323F" (layer "F.Cu")
    (tedit 60F16F6B)
    (at 124.2 134.6 90)
    (property "Author" "Antmicro")
    (property "License" "Apache-2.0")
    (property "MPN" "1N4148WS")
    (property "Manufacturer" "ON Semiconductor")
    (property "Sheetfile" "usb-c-interface.kicad_sch")
    (property "Sheetname" "USB-C Interface ")
    (attr smd)
    (fp_text reference "D6" (at -0.76 -1.07 90) (layer "F.SilkS")
      (effects (font (size 0.7 0.7) (thickness 0.15)) (justify left bottom))
    )
    (fp_text value "1N4148WS" (at -1.7 1.9 90) (layer "F.Fab")
      (effects (font (size 0.7 0.7) (thickness 0.15)) (justify left bottom))
    )
    (fp_text user "${REFERENCE}" (at -1.8 3.2 90) (layer "F.Fab") hide
      (effects (font (size 0.7 0.7) (thickness 0.15)) (justify left bottom))
    )
    (fp_text user "Author: Antmicro" (at -1.8 4.46 90) (layer "F.Fab") hide
      (effects (font (size 0.7 0.7) (thickness 0.15)) (justify left bottom))
    )
    (fp_text user "License: Apache-2.0" (at -1.8 5.8 90) (layer "F.Fab") hide
      (effects (font (size 0.7 0.7) (thickness 0.15)) (justify left bottom))
    )
    (fp_line (start 0.973 -0.75) (end 0.973 -0.45) (layer "F.SilkS") (width 0.15))
    (fp_line (start -0.5 -0.426) (end -0.5 0.424) (layer "F.SilkS") (width 0.15))
    (fp_line (start 0.973 0.748) (end 0.623 0.748) (layer "F.SilkS") (width 0.15))
    (fp_line (start 0.973 0.45) (end 0.973 0.748) (layer "F.SilkS") (width 0.15))
    (fp_line (start 0.623 -0.75) (end 0.973 -0.75) (layer "F.SilkS") (width 0.15))
    (fp_line (start -0.975 -0.75) (end -0.975 -0.45) (layer "F.SilkS") (width 0.15))
    (fp_line (start -0.625 0.748) (end -0.975 0.748) (layer "F.SilkS") (width 0.15))
    (fp_line (start -0.975 0.748) (end -0.975 0.45) (layer "F.SilkS") (width 0.15))
    (fp_line (start -0.625 -0.75) (end -0.975 -0.75) (layer "F.SilkS") (width 0.15))
    (fp_rect (start -1.6 -0.827) (end 1.599 0.825) (layer "F.CrtYd") (width 0.05) (fill none))
    (fp_line (start -0.85 -0.625) (end 0.848 -0.625) (layer "F.Fab") (width 0.15))
    (fp_line (start -0.85 0.623) (end 0.848 0.623) (layer "F.Fab") (width 0.15))
    (fp_line (start 0.848 -0.625) (end 0.848 0.623) (layer "F.Fab") (width 0.15))
    (fp_line (start -0.85 0.623) (end -0.85 -0.625) (layer "F.Fab") (width 0.15))
    (pad "A" smd roundrect (at 1.05 0 90) (size 0.8 0.6) (layers "F.Cu" "F.Paste" "F.Mask") (roundrect_rratio 0.15)
      (net 133 "5V_SYS") (pinfunction "A") (pintype "passive"))
    (pad "K" smd roundrect (at -1.051 0 90) (size 0.8 0.6) (layers "F.Cu" "F.Paste" "F.Mask") (roundrect_rratio 0.15)
      (net 228 "/USB-C Interface /5V0_DBG") (pinfunction "K") (pintype "passive"))
  )
	(footprint "sa800u-baseboard-hw-footprints:FB_0603_1608Metric" (layer "F.Cu")
    (tedit 618B9E9E)
    (at 126.3 140.95 180)
    (property "Author" "Antmicro")
    (property "License" "Apache-2.0")
    (property "MPN" "BLM18EG221SN1D")
    (property "Manufacturer" "Murata")
    (property "Sheetfile" "usb-c-interface.kicad_sch")
    (property "Sheetname" "USB-C Interface ")
    (attr smd)
    (fp_text reference "FB3" (at 3.35 -0.43 180) (layer "F.SilkS")
      (effects (font (size 0.7 0.7) (thickness 0.15)) (justify left bottom))
    )
    (fp_text value "FB_220Z_1A_0603" (at 0 1.5 180) (layer "F.Fab")
      (effects (font (size 0.7 0.7) (thickness 0.15)) (justify left bottom))
    )
    (fp_text user "Author: Antmicro" (at -1.653 3.162 180) (layer "F.Fab") hide
      (effects (font (size 0.7 0.7) (thickness 0.15)) (justify left bottom))
    )
    (fp_text user "${REFERENCE}" (at -1.653 4.6 180) (layer "F.Fab") hide
      (effects (font (size 0.7 0.7) (thickness 0.15)) (justify left bottom))
    )
    (fp_text user "License: Apache-2.0" (at -1.653 5.9 180) (layer "F.Fab") hide
      (effects (font (size 0.7 0.7) (thickness 0.15)) (justify left bottom))
    )
    (fp_line (start -0.196 -0.408) (end 0.193 -0.408) (layer "F.SilkS") (width 0.15))
    (fp_line (start -0.196 0.406) (end 0.193 0.406) (layer "F.SilkS") (width 0.15))
    (fp_rect (start -1.3 -0.6) (end 1.3 0.6) (layer "F.CrtYd") (width 0.05) (fill none))
    (fp_line (start -0.803 0.406) (end -0.803 -0.408) (layer "F.Fab") (width 0.15))
    (fp_line (start 0.8 -0.408) (end -0.803 -0.408) (layer "F.Fab") (width 0.15))
    (fp_line (start 0.8 0.406) (end -0.803 0.406) (layer "F.Fab") (width 0.15))
    (fp_line (start 0.8 -0.408) (end 0.8 0.406) (layer "F.Fab") (width 0.15))
    (pad "1" smd roundrect (at -0.891 0 180) (size 0.762 1.09) (layers "F.Cu" "F.Paste" "F.Mask") (roundrect_rratio 0.15)
      (net 253 "/USB-C Interface /DBG_VBUS") (pintype "passive"))
    (pad "2" smd roundrect (at 0.888 0 180) (size 0.762 1.09) (layers "F.Cu" "F.Paste" "F.Mask") (roundrect_rratio 0.15)
      (net 228 "/USB-C Interface /5V0_DBG") (pintype "passive"))
  )
	(footprint "sa800u-baseboard-hw-footprints:QFN-32-1EP_5x5mm" (layer "F.Cu")
    (tedit 5E53F9B0)
    (at 128.771 136.375)
    (property "Author" "Antmicro")
    (property "License" "Apache-2.0")
    (property "MPN" "FT232RQ-REEL")
    (property "Manufacturer" "FTDI")
    (property "Sheetfile" "usb-c-interface.kicad_sch")
    (property "Sheetname" "USB-C Interface ")
    (attr smd)
    (fp_text reference "U5" (at -3.671 -2.675) (layer "F.SilkS")
      (effects (font (size 0.7 0.7) (thickness 0.15)) (justify left bottom))
    )
    (fp_text value "FT232R_QFN" (at -4.94 3.91) (layer "F.Fab")
      (effects (font (size 0.7 0.7) (thickness 0.15)) (justify left bottom))
    )
    (fp_text user "License: Apache-2.0" (at -4.94 5.91) (layer "F.Fab") hide
      (effects (font (size 0.7 0.7) (thickness 0.15)) (justify left bottom))
    )
    (fp_text user "${REFERENCE}" (at -4.94 7.11) (layer "F.Fab") hide
      (effects (font (size 0.7 0.7) (thickness 0.15)) (justify left bottom))
    )
    (fp_text user "Author: Antmicro" (at -4.94 8.31) (layer "F.Fab") hide
      (effects (font (size 0.7 0.7) (thickness 0.15)) (justify left bottom))
    )
    (fp_line (start 2.58 -2.552) (end 2.177 -2.552) (layer "F.SilkS") (width 0.15))
    (fp_line (start 2.58 -2.552) (end 2.58 -2.149) (layer "F.SilkS") (width 0.15))
    (fp_line (start 2.58 2.648) (end 2.177 2.648) (layer "F.SilkS") (width 0.15))
    (fp_line (start -2.621 2.648) (end -2.621 2.249) (layer "F.SilkS") (width 0.15))
    (fp_line (start -2.222 -2.552) (end -2.621 -2.149) (layer "F.SilkS") (width 0.15))
    (fp_line (start -2.222 2.648) (end -2.621 2.648) (layer "F.SilkS") (width 0.15))
    (fp_line (start 2.58 2.249) (end 2.58 2.648) (layer "F.SilkS") (width 0.15))
    (fp_circle (center -3.3 -1.702) (end -3.25 -1.702) (layer "F.SilkS") (width 0.15) (fill solid))
    (fp_rect (start -3 -3) (end 2.999 2.999) (layer "F.CrtYd") (width 0.05) (fill none))
    (fp_line (start -2.5 -2.299) (end -2.299 -2.5) (layer "F.Fab") (width 0.15))
    (fp_rect (start -2.5 -2.5) (end 2.499 2.499) (layer "F.Fab") (width 0.15) (fill none))
    (pad "1" smd rect (at -2.496 -1.702 270) (size 0.28 0.85) (layers "F.Cu" "F.Paste" "F.Mask")
      (net 127 "1V8_DBG") (pinfunction "VCCIO") (pintype "power_in") (solder_mask_margin 0.07))
    (pad "2" smd rect (at -2.496 -1.2 270) (size 0.28 0.85) (layers "F.Cu" "F.Paste" "F.Mask")
      (net 130 "DBG_TXD") (pinfunction "RXD") (pintype "input") (solder_mask_margin 0.07))
    (pad "3" smd rect (at -2.496 -0.702 270) (size 0.28 0.85) (layers "F.Cu" "F.Paste" "F.Mask")
      (net 504 "unconnected-(U5-Pad3)") (pinfunction "RI#") (pintype "input+no_connect") (solder_mask_margin 0.07))
    (pad "4" smd rect (at -2.496 -0.202 270) (size 0.28 0.85) (layers "F.Cu" "F.Paste" "F.Mask")
      (net 1 "GND") (pinfunction "GND") (pintype "passive") (solder_mask_margin 0.07))
    (pad "5" smd rect (at -2.496 0.297 270) (size 0.28 0.85) (layers "F.Cu" "F.Paste" "F.Mask")
      (net 503 "unconnected-(U5-Pad5)") (pinfunction "NC") (pintype "no_connect") (solder_mask_margin 0.07))
    (pad "6" smd rect (at -2.496 0.8 270) (size 0.28 0.85) (layers "F.Cu" "F.Paste" "F.Mask")
      (net 502 "unconnected-(U5-Pad6)") (pinfunction "DSR#") (pintype "input+no_connect") (solder_mask_margin 0.07))
    (pad "7" smd rect (at -2.496 1.3 270) (size 0.28 0.85) (layers "F.Cu" "F.Paste" "F.Mask")
      (net 501 "unconnected-(U5-Pad7)") (pinfunction "DCD#") (pintype "input+no_connect") (solder_mask_margin 0.07))
    (pad "8" smd rect (at -2.496 1.8 270) (size 0.28 0.85) (layers "F.Cu" "F.Paste" "F.Mask")
      (net 500 "unconnected-(U5-Pad8)") (pinfunction "CTS#") (pintype "input+no_connect") (solder_mask_margin 0.07))
    (pad "9" smd rect (at -1.77 2.523 270) (size 0.85 0.28) (layers "F.Cu" "F.Paste" "F.Mask")
      (net 499 "unconnected-(U5-Pad9)") (pinfunction "CBUS4") (pintype "bidirectional+no_connect") (solder_mask_margin 0.07))
    (pad "10" smd rect (at -1.27 2.523 270) (size 0.85 0.28) (layers "F.Cu" "F.Paste" "F.Mask")
      (net 498 "unconnected-(U5-Pad10)") (pinfunction "CBUS2") (pintype "bidirectional+no_connect") (solder_mask_margin 0.07))
    (pad "11" smd rect (at -0.773 2.523 270) (size 0.85 0.28) (layers "F.Cu" "F.Paste" "F.Mask")
      (net 497 "unconnected-(U5-Pad11)") (pinfunction "CBUS3") (pintype "bidirectional+no_connect") (solder_mask_margin 0.07))
    (pad "12" smd rect (at -0.273 2.523 270) (size 0.85 0.28) (layers "F.Cu" "F.Paste" "F.Mask")
      (net 496 "unconnected-(U5-Pad12)") (pinfunction "NC") (pintype "no_connect") (solder_mask_margin 0.07))
    (pad "13" smd rect (at 0.229 2.523 270) (size 0.85 0.28) (layers "F.Cu" "F.Paste" "F.Mask")
      (net 495 "unconnected-(U5-Pad13)") (pinfunction "NC") (pintype "no_connect") (solder_mask_margin 0.07))
    (pad "14" smd rect (at 0.727 2.523 270) (size 0.85 0.28) (layers "F.Cu" "F.Paste" "F.Mask")
      (net 230 "/USB-C Interface /DBG_USB_D_P") (pinfunction "USBDP") (pintype "bidirectional") (solder_mask_margin 0.07))
    (pad "15" smd rect (at 1.229 2.523 270) (size 0.85 0.28) (layers "F.Cu" "F.Paste" "F.Mask")
      (net 229 "/USB-C Interface /DBG_USB_D_N") (pinfunction "USBDM") (pintype "bidirectional") (solder_mask_margin 0.07))
    (pad "16" smd rect (at 1.729 2.523 270) (size 0.85 0.28) (layers "F.Cu" "F.Paste" "F.Mask")
      (net 352 "Net-(C67-Pad1)") (pinfunction "3V3OUT") (pintype "output") (solder_mask_margin 0.07))
    (pad "17" smd rect (at 2.455 1.8 270) (size 0.28 0.85) (layers "F.Cu" "F.Paste" "F.Mask")
      (net 1 "GND") (pinfunction "GND") (pintype "power_in") (solder_mask_margin 0.07))
    (pad "18" smd rect (at 2.455 1.3 270) (size 0.28 0.85) (layers "F.Cu" "F.Paste" "F.Mask")
      (net 494 "unconnected-(U5-Pad18)") (pinfunction "RESET#") (pintype "input+no_connect") (solder_mask_margin 0.07))
    (pad "19" smd rect (at 2.455 0.8 270) (size 0.28 0.85) (layers "F.Cu" "F.Paste" "F.Mask")
      (net 228 "/USB-C Interface /5V0_DBG") (pinfunction "VCC") (pintype "power_in") (solder_mask_margin 0.07))
    (pad "20" smd rect (at 2.455 0.297 270) (size 0.28 0.85) (layers "F.Cu" "F.Paste" "F.Mask")
      (net 1 "GND") (pinfunction "GND") (pintype "passive") (solder_mask_margin 0.07))
    (pad "21" smd rect (at 2.455 -0.202 270) (size 0.28 0.85) (layers "F.Cu" "F.Paste" "F.Mask")
      (net 493 "unconnected-(U5-Pad21)") (pinfunction "CBUS1") (pintype "bidirectional+no_connect") (solder_mask_margin 0.07))
    (pad "22" smd rect (at 2.455 -0.702 270) (size 0.28 0.85) (layers "F.Cu" "F.Paste" "F.Mask")
      (net 492 "unconnected-(U5-Pad22)") (pinfunction "CBUS0") (pintype "bidirectional+no_connect") (solder_mask_margin 0.07))
    (pad "23" smd rect (at 2.455 -1.2 270) (size 0.28 0.85) (layers "F.Cu" "F.Paste" "F.Mask")
      (net 491 "unconnected-(U5-Pad23)") (pinfunction "NC") (pintype "no_connect") (solder_mask_margin 0.07))
    (pad "24" smd rect (at 2.455 -1.702 270) (size 0.28 0.85) (layers "F.Cu" "F.Paste" "F.Mask")
      (net 1 "GND") (pinfunction "AGND") (pintype "power_in") (solder_mask_margin 0.07))
    (pad "25" smd rect (at 1.729 -2.427 270) (size 0.85 0.28) (layers "F.Cu" "F.Paste" "F.Mask")
      (net 490 "unconnected-(U5-Pad25)") (pinfunction "NC") (pintype "no_connect") (solder_mask_margin 0.07))
    (pad "26" smd rect (at 1.229 -2.427 270) (size 0.85 0.28) (layers "F.Cu" "F.Paste" "F.Mask")
      (net 1 "GND") (pinfunction "TEST") (pintype "input") (solder_mask_margin 0.07))
    (pad "27" smd rect (at 0.727 -2.427 270) (size 0.85 0.28) (layers "F.Cu" "F.Paste" "F.Mask")
      (net 489 "unconnected-(U5-Pad27)") (pinfunction "OSCI") (pintype "input+no_connect") (solder_mask_margin 0.07))
    (pad "28" smd rect (at 0.229 -2.427 270) (size 0.85 0.28) (layers "F.Cu" "F.Paste" "F.Mask")
      (net 488 "unconnected-(U5-Pad28)") (pinfunction "OSCO") (pintype "output+no_connect") (solder_mask_margin 0.07))
    (pad "29" smd rect (at -0.273 -2.427 270) (size 0.85 0.28) (layers "F.Cu" "F.Paste" "F.Mask")
      (net 487 "unconnected-(U5-Pad29)") (pinfunction "NC") (pintype "no_connect") (solder_mask_margin 0.07))
    (pad "30" smd rect (at -0.773 -2.427 270) (size 0.85 0.28) (layers "F.Cu" "F.Paste" "F.Mask")
      (net 129 "DBG_RXD") (pinfunction "TXD") (pintype "output") (solder_mask_margin 0.07))
    (pad "31" smd rect (at -1.27 -2.427 270) (size 0.85 0.28) (layers "F.Cu" "F.Paste" "F.Mask")
      (net 486 "unconnected-(U5-Pad31)") (pinfunction "DTR#") (pintype "output+no_connect") (solder_mask_margin 0.07))
    (pad "32" smd rect (at -1.77 -2.427 270) (size 0.85 0.28) (layers "F.Cu" "F.Paste" "F.Mask")
      (net 485 "unconnected-(U5-Pad32)") (pinfunction "RTS#") (pintype "output+no_connect") (solder_mask_margin 0.07))
    (pad "33" smd rect (at -0.022 0.049 270) (size 3.45 3.45) (layers "F.Cu" "F.Paste" "F.Mask")
      (net 1 "GND") (pinfunction "EP") (pintype "unspecified"))
  )
)
